(kicad_pcb
	(version 20260206)
	(generator "pcbnew")
	(generator_version "10.0")
	(general
		(thickness 1.6)
		(legacy_teardrops no)
	)
	(paper "A4")
	(title_block
		(title "01162023_DA0F0TEBIF0_F0T_Expander_BD_F_brd_V02_OCP.brd")
		(comment 1 "Grand Teton / footprints 837-843 of 9728")
	)
	(layers
		(0 "F.Cu" signal "TOP")
		(4 "In1.Cu" signal "GND")
		(6 "In2.Cu" signal "VCC")
		(8 "In3.Cu" signal "VCC1")
		(10 "In4.Cu" signal "GND1")
		(12 "In5.Cu" signal "IN1")
		(14 "In6.Cu" signal "GND2")
		(16 "In7.Cu" signal "IN2")
		(18 "In8.Cu" signal "GND3")
		(20 "In9.Cu" signal "IN3")
		(22 "In10.Cu" signal "GND4")
		(24 "In11.Cu" signal "IN4")
		(26 "In12.Cu" signal "GND5")
		(28 "In13.Cu" signal "IN5")
		(30 "In14.Cu" signal "GND6")
		(32 "In15.Cu" signal "IN6")
		(34 "In16.Cu" signal "GND7")
		(2 "B.Cu" signal "BOTTOM")
		(9 "F.Adhes" user "F.Adhesive")
		(11 "B.Adhes" user "B.Adhesive")
		(13 "F.Paste" user "Package Geometry/Pastemask Top")
		(15 "B.Paste" user "Package Geometry/Pastemask Bottom")
		(5 "F.SilkS" user "Ref Des/Silkscreen Top")
		(7 "B.SilkS" user "Ref Des/Silkscreen Bottom")
		(1 "F.Mask" user "Board Geometry/Soldermask Top")
		(3 "B.Mask" user "Board Geometry/Soldermask Bottom")
		(17 "Dwgs.User" user "User.Drawings")
		(19 "Cmts.User" user "User.Comments")
		(21 "Eco1.User" user "User.Eco1")
		(23 "Eco2.User" user "User.Eco2")
		(25 "Edge.Cuts" user "Board Geometry/Outline")
		(27 "Margin" user)
		(31 "F.CrtYd" user "Package Geometry/Place Bound Top")
		(29 "B.CrtYd" user "Package Geometry/Place Bound Bottom")
		(35 "F.Fab" user "Ref Des/Assembly Top")
		(33 "B.Fab" user "Ref Des/Assembly Bottom")
	)
	(footprint ""
		(layer "F.Cu")
		(at 355.913436 -140.392404 180)
		(property "Reference" "PC339"
			(at 0 0 180)
			(layer "F.SilkS")
			(hide yes)
			(effects
				(font
					(size 1.27 1.27)
				)
			)
		)
		(property "Value" ""
			(at 0 0 180)
			(layer "F.Fab")
			(effects
				(font
					(size 1.27 1.27)
				)
			)
		)
		(duplicate_pad_numbers_are_jumpers no)
		(fp_line
			(start 0.7874 0.4064)
			(end -0.7874 0.4064)
			(stroke
				(width 0.1524)
				(type default)
			)
			(layer "F.SilkS")
		)
		(fp_line
			(start 0.7874 -0.4064)
			(end 0.7874 0.4064)
			(stroke
				(width 0.1524)
				(type default)
			)
			(layer "F.SilkS")
		)
		(fp_line
			(start -0.7874 0.4064)
			(end -0.7874 -0.4064)
			(stroke
				(width 0.1524)
				(type default)
			)
			(layer "F.SilkS")
		)
		(fp_line
			(start -0.7874 -0.4064)
			(end 0.7874 -0.4064)
			(stroke
				(width 0.1524)
				(type default)
			)
			(layer "F.SilkS")
		)
		(fp_line
			(start 0.6858 0.3048)
			(end 0.1016 0.3048)
			(stroke
				(width 0.1)
				(type default)
			)
			(layer "F.Fab")
		)
		(fp_line
			(start 0.6858 -0.3048)
			(end 0.6858 0.3048)
			(stroke
				(width 0.1)
				(type default)
			)
			(layer "F.Fab")
		)
		(fp_line
			(start 0.1016 0.3048)
			(end 0.1016 0.2794)
			(stroke
				(width 0.1)
				(type default)
			)
			(layer "F.Fab")
		)
		(fp_line
			(start 0.1016 0.2794)
			(end -0.1016 0.2794)
			(stroke
				(width 0.1)
				(type default)
			)
			(layer "F.Fab")
		)
		(fp_line
			(start 0.1016 -0.2794)
			(end 0.1016 -0.3048)
			(stroke
				(width 0.1)
				(type default)
			)
			(layer "F.Fab")
		)
		(fp_line
			(start 0.1016 -0.3048)
			(end 0.6858 -0.3048)
			(stroke
				(width 0.1)
				(type default)
			)
			(layer "F.Fab")
		)
		(fp_line
			(start -0.1016 0.3048)
			(end -0.6858 0.3048)
			(stroke
				(width 0.1)
				(type default)
			)
			(layer "F.Fab")
		)
		(fp_line
			(start -0.1016 0.2794)
			(end -0.1016 0.3048)
			(stroke
				(width 0.1)
				(type default)
			)
			(layer "F.Fab")
		)
		(fp_line
			(start -0.1016 -0.2794)
			(end 0.1016 -0.2794)
			(stroke
				(width 0.1)
				(type default)
			)
			(layer "F.Fab")
		)
		(fp_line
			(start -0.1016 -0.3048)
			(end -0.1016 -0.2794)
			(stroke
				(width 0.1)
				(type default)
			)
			(layer "F.Fab")
		)
		(fp_line
			(start -0.6858 0.3048)
			(end -0.6858 -0.3048)
			(stroke
				(width 0.1)
				(type default)
			)
			(layer "F.Fab")
		)
		(fp_line
			(start -0.6858 -0.3048)
			(end -0.1016 -0.3048)
			(stroke
				(width 0.1)
				(type default)
			)
			(layer "F.Fab")
		)
		(pad "1" smd rect
			(at -0.40005 0)
			(size 0.4572 0.508)
			(layers "F.Cu" "F.Mask" "F.Paste")
			(net "P12V_NIC6_SS")
		)
		(pad "2" smd rect
			(at 0.40005 0)
			(size 0.4572 0.508)
			(layers "F.Cu" "F.Mask" "F.Paste")
			(net "GND")
		)
	)
	(footprint ""
		(layer "F.Cu")
		(at 307.856382 -20.467574 180)
		(property "Reference" "R1703"
			(at 0 0 180)
			(layer "F.SilkS")
			(hide yes)
			(effects
				(font
					(size 1.27 1.27)
				)
			)
		)
		(property "Value" ""
			(at 0 0 180)
			(layer "F.Fab")
			(effects
				(font
					(size 1.27 1.27)
				)
			)
		)
		(duplicate_pad_numbers_are_jumpers no)
		(fp_line
			(start 0.7874 0.4064)
			(end -0.7874 0.4064)
			(stroke
				(width 0.1524)
				(type default)
			)
			(layer "F.SilkS")
		)
		(fp_line
			(start 0.7874 -0.4064)
			(end 0.7874 0.4064)
			(stroke
				(width 0.1524)
				(type default)
			)
			(layer "F.SilkS")
		)
		(fp_line
			(start -0.7874 0.4064)
			(end -0.7874 -0.4064)
			(stroke
				(width 0.1524)
				(type default)
			)
			(layer "F.SilkS")
		)
		(fp_line
			(start -0.7874 -0.4064)
			(end 0.7874 -0.4064)
			(stroke
				(width 0.1524)
				(type default)
			)
			(layer "F.SilkS")
		)
		(fp_line
			(start 0.67945 0.3048)
			(end 0.120396 0.3048)
			(stroke
				(width 0.1)
				(type default)
			)
			(layer "F.Fab")
		)
		(fp_line
			(start 0.67945 -0.3048)
			(end 0.67945 0.3048)
			(stroke
				(width 0.1)
				(type default)
			)
			(layer "F.Fab")
		)
		(fp_line
			(start 0.12065 -0.2794)
			(end 0.12065 -0.3048)
			(stroke
				(width 0.1)
				(type default)
			)
			(layer "F.Fab")
		)
		(fp_line
			(start 0.12065 -0.3048)
			(end 0.67945 -0.3048)
			(stroke
				(width 0.1)
				(type default)
			)
			(layer "F.Fab")
		)
		(fp_line
			(start 0.120396 0.3048)
			(end 0.120396 0.2794)
			(stroke
				(width 0.1)
				(type default)
			)
			(layer "F.Fab")
		)
		(fp_line
			(start 0.120396 0.2794)
			(end -0.12065 0.2794)
			(stroke
				(width 0.1)
				(type default)
			)
			(layer "F.Fab")
		)
		(fp_line
			(start -0.12065 0.3048)
			(end -0.67945 0.3048)
			(stroke
				(width 0.1)
				(type default)
			)
			(layer "F.Fab")
		)
		(fp_line
			(start -0.12065 0.2794)
			(end -0.12065 0.3048)
			(stroke
				(width 0.1)
				(type default)
			)
			(layer "F.Fab")
		)
		(fp_line
			(start -0.12065 -0.2794)
			(end 0.12065 -0.2794)
			(stroke
				(width 0.1)
				(type default)
			)
			(layer "F.Fab")
		)
		(fp_line
			(start -0.12065 -0.305054)
			(end -0.12065 -0.2794)
			(stroke
				(width 0.1)
				(type default)
			)
			(layer "F.Fab")
		)
		(fp_line
			(start -0.67945 0.3048)
			(end -0.67945 -0.305054)
			(stroke
				(width 0.1)
				(type default)
			)
			(layer "F.Fab")
		)
		(fp_line
			(start -0.67945 -0.305054)
			(end -0.12065 -0.305054)
			(stroke
				(width 0.1)
				(type default)
			)
			(layer "F.Fab")
		)
		(pad "1" smd circle
			(at -0.40005 0 180)
			(size 0 0)
			(layers "F.Cu" "F.Mask" "F.Paste")
			(net "P3V3_SSD10")
		)
		(pad "2" smd circle
			(at 0.40005 0 180)
			(size 0 0)
			(layers "F.Cu" "F.Mask" "F.Paste")
			(net "SMB_ISO_SSD10_SDA")
		)
	)
	(footprint ""
		(layer "F.Cu")
		(at 287.439862 -350.098614 90)
		(property "Reference" "C595"
			(at 0 0 90)
			(layer "F.SilkS")
			(hide yes)
			(effects
				(font
					(size 1.27 1.27)
				)
			)
		)
		(property "Value" ""
			(at 0 0 90)
			(layer "F.Fab")
			(effects
				(font
					(size 1.27 1.27)
				)
			)
		)
		(duplicate_pad_numbers_are_jumpers no)
		(fp_line
			(start 0.299974 -0.150114)
			(end 0.299974 0.150114)
			(stroke
				(width 0.1)
				(type default)
			)
			(layer "F.Fab")
		)
		(fp_line
			(start -0.299974 -0.150114)
			(end 0.299974 -0.150114)
			(stroke
				(width 0.1)
				(type default)
			)
			(layer "F.Fab")
		)
		(fp_line
			(start 0.299974 0.150114)
			(end -0.299974 0.150114)
			(stroke
				(width 0.1)
				(type default)
			)
			(layer "F.Fab")
		)
		(fp_line
			(start -0.299974 0.150114)
			(end -0.299974 -0.150114)
			(stroke
				(width 0.1)
				(type default)
			)
			(layer "F.Fab")
		)
		(pad "1" smd rect
			(at -0.2667 0 90)
			(size 0.3048 0.381)
			(layers "F.Cu" "F.Mask" "F.Paste")
			(net "P5E_PEX2_STN7_TX_DP<121>")
		)
		(pad "2" smd rect
			(at 0.2667 0 90)
			(size 0.3048 0.381)
			(layers "F.Cu" "F.Mask" "F.Paste")
			(net "P5E_PEX2_STN7_TX_C_DP<121>")
		)
	)
	(footprint ""
		(layer "F.Cu")
		(at 368.425476 -42.849038 180)
		(property "Reference" "R645"
			(at 0 0 180)
			(layer "F.SilkS")
			(hide yes)
			(effects
				(font
					(size 1.27 1.27)
				)
			)
		)
		(property "Value" ""
			(at 0 0 180)
			(layer "F.Fab")
			(effects
				(font
					(size 1.27 1.27)
				)
			)
		)
		(duplicate_pad_numbers_are_jumpers no)
		(fp_line
			(start 0.7874 0.4064)
			(end -0.7874 0.4064)
			(stroke
				(width 0.1524)
				(type default)
			)
			(layer "F.SilkS")
		)
		(fp_line
			(start 0.7874 -0.4064)
			(end 0.7874 0.4064)
			(stroke
				(width 0.1524)
				(type default)
			)
			(layer "F.SilkS")
		)
		(fp_line
			(start -0.7874 0.4064)
			(end -0.7874 -0.4064)
			(stroke
				(width 0.1524)
				(type default)
			)
			(layer "F.SilkS")
		)
		(fp_line
			(start -0.7874 -0.4064)
			(end 0.7874 -0.4064)
			(stroke
				(width 0.1524)
				(type default)
			)
			(layer "F.SilkS")
		)
		(fp_line
			(start 0.67945 0.3048)
			(end 0.120396 0.3048)
			(stroke
				(width 0.1)
				(type default)
			)
			(layer "F.Fab")
		)
		(fp_line
			(start 0.67945 -0.3048)
			(end 0.67945 0.3048)
			(stroke
				(width 0.1)
				(type default)
			)
			(layer "F.Fab")
		)
		(fp_line
			(start 0.12065 -0.2794)
			(end 0.12065 -0.3048)
			(stroke
				(width 0.1)
				(type default)
			)
			(layer "F.Fab")
		)
		(fp_line
			(start 0.12065 -0.3048)
			(end 0.67945 -0.3048)
			(stroke
				(width 0.1)
				(type default)
			)
			(layer "F.Fab")
		)
		(fp_line
			(start 0.120396 0.3048)
			(end 0.120396 0.2794)
			(stroke
				(width 0.1)
				(type default)
			)
			(layer "F.Fab")
		)
		(fp_line
			(start 0.120396 0.2794)
			(end -0.12065 0.2794)
			(stroke
				(width 0.1)
				(type default)
			)
			(layer "F.Fab")
		)
		(fp_line
			(start -0.12065 0.3048)
			(end -0.67945 0.3048)
			(stroke
				(width 0.1)
				(type default)
			)
			(layer "F.Fab")
		)
		(fp_line
			(start -0.12065 0.2794)
			(end -0.12065 0.3048)
			(stroke
				(width 0.1)
				(type default)
			)
			(layer "F.Fab")
		)
		(fp_line
			(start -0.12065 -0.2794)
			(end 0.12065 -0.2794)
			(stroke
				(width 0.1)
				(type default)
			)
			(layer "F.Fab")
		)
		(fp_line
			(start -0.12065 -0.305054)
			(end -0.12065 -0.2794)
			(stroke
				(width 0.1)
				(type default)
			)
			(layer "F.Fab")
		)
		(fp_line
			(start -0.67945 0.3048)
			(end -0.67945 -0.305054)
			(stroke
				(width 0.1)
				(type default)
			)
			(layer "F.Fab")
		)
		(fp_line
			(start -0.67945 -0.305054)
			(end -0.12065 -0.305054)
			(stroke
				(width 0.1)
				(type default)
			)
			(layer "F.Fab")
		)
		(pad "1" smd circle
			(at -0.40005 0 180)
			(size 0 0)
			(layers "F.Cu" "F.Mask" "F.Paste")
			(net "P12V_SSD12_R")
		)
		(pad "2" smd circle
			(at 0.40005 0 180)
			(size 0 0)
			(layers "F.Cu" "F.Mask" "F.Paste")
			(net "P12V_SSD12_VIN_P")
		)
	)
	(footprint ""
		(layer "F.Cu")
		(at 263.856216 -61.487812 180)
		(property "Reference" "R5993"
			(at 0 0 180)
			(layer "F.SilkS")
			(hide yes)
			(effects
				(font
					(size 1.27 1.27)
				)
			)
		)
		(property "Value" ""
			(at 0 0 180)
			(layer "F.Fab")
			(effects
				(font
					(size 1.27 1.27)
				)
			)
		)
		(duplicate_pad_numbers_are_jumpers no)
		(fp_line
			(start 0.7874 0.4064)
			(end -0.7874 0.4064)
			(stroke
				(width 0.1524)
				(type default)
			)
			(layer "F.SilkS")
		)
		(fp_line
			(start 0.7874 -0.4064)
			(end 0.7874 0.4064)
			(stroke
				(width 0.1524)
				(type default)
			)
			(layer "F.SilkS")
		)
		(fp_line
			(start -0.7874 0.4064)
			(end -0.7874 -0.4064)
			(stroke
				(width 0.1524)
				(type default)
			)
			(layer "F.SilkS")
		)
		(fp_line
			(start -0.7874 -0.4064)
			(end 0.7874 -0.4064)
			(stroke
				(width 0.1524)
				(type default)
			)
			(layer "F.SilkS")
		)
		(fp_line
			(start 0.67945 0.3048)
			(end 0.120396 0.3048)
			(stroke
				(width 0.1)
				(type default)
			)
			(layer "F.Fab")
		)
		(fp_line
			(start 0.67945 -0.3048)
			(end 0.67945 0.3048)
			(stroke
				(width 0.1)
				(type default)
			)
			(layer "F.Fab")
		)
		(fp_line
			(start 0.12065 -0.2794)
			(end 0.12065 -0.3048)
			(stroke
				(width 0.1)
				(type default)
			)
			(layer "F.Fab")
		)
		(fp_line
			(start 0.12065 -0.3048)
			(end 0.67945 -0.3048)
			(stroke
				(width 0.1)
				(type default)
			)
			(layer "F.Fab")
		)
		(fp_line
			(start 0.120396 0.3048)
			(end 0.120396 0.2794)
			(stroke
				(width 0.1)
				(type default)
			)
			(layer "F.Fab")
		)
		(fp_line
			(start 0.120396 0.2794)
			(end -0.12065 0.2794)
			(stroke
				(width 0.1)
				(type default)
			)
			(layer "F.Fab")
		)
		(fp_line
			(start -0.12065 0.3048)
			(end -0.67945 0.3048)
			(stroke
				(width 0.1)
				(type default)
			)
			(layer "F.Fab")
		)
		(fp_line
			(start -0.12065 0.2794)
			(end -0.12065 0.3048)
			(stroke
				(width 0.1)
				(type default)
			)
			(layer "F.Fab")
		)
		(fp_line
			(start -0.12065 -0.2794)
			(end 0.12065 -0.2794)
			(stroke
				(width 0.1)
				(type default)
			)
			(layer "F.Fab")
		)
		(fp_line
			(start -0.12065 -0.305054)
			(end -0.12065 -0.2794)
			(stroke
				(width 0.1)
				(type default)
			)
			(layer "F.Fab")
		)
		(fp_line
			(start -0.67945 0.3048)
			(end -0.67945 -0.305054)
			(stroke
				(width 0.1)
				(type default)
			)
			(layer "F.Fab")
		)
		(fp_line
			(start -0.67945 -0.305054)
			(end -0.12065 -0.305054)
			(stroke
				(width 0.1)
				(type default)
			)
			(layer "F.Fab")
		)
		(pad "1" smd circle
			(at -0.40005 0 180)
			(size 0 0)
			(layers "F.Cu" "F.Mask" "F.Paste")
			(net "P3V3_AUX")
		)
		(pad "2" smd circle
			(at 0.40005 0 180)
			(size 0 0)
			(layers "F.Cu" "F.Mask" "F.Paste")
			(net "PWRGD_P12V_SSD9_D")
		)
	)
	(footprint ""
		(layer "F.Cu")
		(at 54.404514 -362.580682 90)
		(property "Reference" "R6734"
			(at 0 0 90)
			(layer "F.SilkS")
			(hide yes)
			(effects
				(font
					(size 1.27 1.27)
				)
			)
		)
		(property "Value" ""
			(at 0 0 90)
			(layer "F.Fab")
			(effects
				(font
					(size 1.27 1.27)
				)
			)
		)
		(duplicate_pad_numbers_are_jumpers no)
		(fp_line
			(start 0.7874 -0.4064)
			(end 0.7874 0.4064)
			(stroke
				(width 0.1524)
				(type default)
			)
			(layer "F.SilkS")
		)
		(fp_line
			(start -0.7874 -0.4064)
			(end 0.7874 -0.4064)
			(stroke
				(width 0.1524)
				(type default)
			)
			(layer "F.SilkS")
		)
		(fp_line
			(start 0.04318 0.4064)
			(end -0.7874 0.4064)
			(stroke
				(width 0.1524)
				(type default)
			)
			(layer "F.SilkS")
		)
		(fp_line
			(start -0.12065 -0.305054)
			(end -0.12065 -0.2794)
			(stroke
				(width 0.1)
				(type default)
			)
			(layer "F.Fab")
		)
		(fp_line
			(start -0.67945 -0.305054)
			(end -0.12065 -0.305054)
			(stroke
				(width 0.1)
				(type default)
			)
			(layer "F.Fab")
		)
		(fp_line
			(start 0.67945 -0.3048)
			(end 0.67945 0.3048)
			(stroke
				(width 0.1)
				(type default)
			)
			(layer "F.Fab")
		)
		(fp_line
			(start 0.12065 -0.3048)
			(end 0.67945 -0.3048)
			(stroke
				(width 0.1)
				(type default)
			)
			(layer "F.Fab")
		)
		(fp_line
			(start 0.12065 -0.2794)
			(end 0.12065 -0.3048)
			(stroke
				(width 0.1)
				(type default)
			)
			(layer "F.Fab")
		)
		(fp_line
			(start -0.12065 -0.2794)
			(end 0.12065 -0.2794)
			(stroke
				(width 0.1)
				(type default)
			)
			(layer "F.Fab")
		)
		(fp_line
			(start 0.120396 0.2794)
			(end -0.12065 0.2794)
			(stroke
				(width 0.1)
				(type default)
			)
			(layer "F.Fab")
		)
		(fp_line
			(start -0.12065 0.2794)
			(end -0.12065 0.3048)
			(stroke
				(width 0.1)
				(type default)
			)
			(layer "F.Fab")
		)
		(fp_line
			(start 0.67945 0.3048)
			(end 0.120396 0.3048)
			(stroke
				(width 0.1)
				(type default)
			)
			(layer "F.Fab")
		)
		(fp_line
			(start 0.120396 0.3048)
			(end 0.120396 0.2794)
			(stroke
				(width 0.1)
				(type default)
			)
			(layer "F.Fab")
		)
		(fp_line
			(start -0.12065 0.3048)
			(end -0.67945 0.3048)
			(stroke
				(width 0.1)
				(type default)
			)
			(layer "F.Fab")
		)
		(fp_line
			(start -0.67945 0.3048)
			(end -0.67945 -0.305054)
			(stroke
				(width 0.1)
				(type default)
			)
			(layer "F.Fab")
		)
		(pad "1" smd rect
			(at -0.40005 0 270)
			(size 0.4572 0.508)
			(layers "F.Cu" "F.Mask" "F.Paste")
			(net "USB2_GPU_HMC_USB8042_DN")
		)
		(pad "2" smd rect
			(at 0.40005 0 270)
			(size 0.4572 0.508)
			(layers "F.Cu" "F.Mask" "F.Paste")
			(net "USB2_GPU_HMC_DN")
		)
	)
	(footprint ""
		(layer "F.Cu")
		(at 17.792446 -32.739584 180)
		(property "Reference" "C67"
			(at 0 0 180)
			(layer "F.SilkS")
			(hide yes)
			(effects
				(font
					(size 1.27 1.27)
				)
			)
		)
		(property "Value" ""
			(at 0 0 180)
			(layer "F.Fab")
			(effects
				(font
					(size 1.27 1.27)
				)
			)
		)
		(duplicate_pad_numbers_are_jumpers no)
		(fp_line
			(start 0.299974 0.150114)
			(end -0.299974 0.150114)
			(stroke
				(width 0.1)
				(type default)
			)
			(layer "F.Fab")
		)
		(fp_line
			(start 0.299974 -0.150114)
			(end 0.299974 0.150114)
			(stroke
				(width 0.1)
				(type default)
			)
			(layer "F.Fab")
		)
		(fp_line
			(start -0.299974 0.150114)
			(end -0.299974 -0.150114)
			(stroke
				(width 0.1)
				(type default)
			)
			(layer "F.Fab")
		)
		(fp_line
			(start -0.299974 -0.150114)
			(end 0.299974 -0.150114)
			(stroke
				(width 0.1)
				(type default)
			)
			(layer "F.Fab")
		)
		(pad "1" smd rect
			(at -0.2667 0 180)
			(size 0.3048 0.381)
			(layers "F.Cu" "F.Mask" "F.Paste")
			(net "P5E_PEX0_STN2_TX_DP<46>")
		)
		(pad "2" smd rect
			(at 0.2667 0 180)
			(size 0.3048 0.381)
			(layers "F.Cu" "F.Mask" "F.Paste")
			(net "P5E_PEX0_STN2_TX_C_DP<46>")
		)
	)
)
